# S9S_MB_2U (Grand Teton) — schematic netlist excerpt (pin names and nets, part order shuffled) for the footprints in the layout excerpt that follows; sources: Cadence DE-HDL packaged netlist, KiCad conversion of 03242023_DA0F0TMBIJ0_F0T_Motherboard_J_brd_V01_OCP.brd

C909  Q_CAP_DIFFBUS  DIFF BUS_0.22UF 6.3V 20% X6S  pkg C0201  page 173 : \1\ = P5E_CPU0_PE0_TX_C_DP<12> ; \2\ = P5E_CPU0_PE0_TX_DP<12>
H86  HOLE  EMPTY  pkg TH  page 311 : \1\ = GND
C814  Q_CAP_DIFFBUS  DIFF BUS_0.22UF 6.3V 20% X6S  pkg C0201  page 175 : \1\ = P5E_CPU1_PE1_TX_C_DN<11> ; \2\ = P5E_CPU1_PE1_TX_DN<11>

U337  LM4040AIM3X25NOPB  LM4040AIM3X-2.5/NOPB EMPTY  pkg SOT23_123_2-92X1-3  page 307
  \1+\  = UV_ADR_P2V5_COMP
  \2-\  = GND
  \3\  = NC

(kicad_pcb
	(version 20260206)
	(generator "pcbnew")
	(generator_version "10.0")
	(general
		(thickness 1.6)
		(legacy_teardrops no)
	)
	(paper "A4")
	(title_block
		(title "03242023_DA0F0TMBIJ0_F0T_Motherboard_J_brd_V01_OCP.brd")
		(comment 1 "Grand Teton / footprints 2790-2793 of 6105")
	)
	(layers
		(0 "F.Cu" signal "TOP")
		(4 "In1.Cu" signal "GND")
		(6 "In2.Cu" signal "IN1")
		(8 "In3.Cu" signal "GND1")
		(10 "In4.Cu" signal "IN2")
		(12 "In5.Cu" signal "GND2")
		(14 "In6.Cu" signal "IN3")
		(16 "In7.Cu" signal "GND3")
		(18 "In8.Cu" signal "VCC")
		(20 "In9.Cu" signal "VCC1")
		(22 "In10.Cu" signal "GND4")
		(24 "In11.Cu" signal "IN4")
		(26 "In12.Cu" signal "GND5")
		(28 "In13.Cu" signal "IN5")
		(30 "In14.Cu" signal "GND6")
		(32 "In15.Cu" signal "IN6")
		(34 "In16.Cu" signal "GND7")
		(2 "B.Cu" signal "BOTTOM")
		(9 "F.Adhes" user "F.Adhesive")
		(11 "B.Adhes" user "B.Adhesive")
		(13 "F.Paste" user "Package Geometry/Pastemask Top")
		(15 "B.Paste" user "Package Geometry/Pastemask Bottom")
		(5 "F.SilkS" user "Ref Des/Silkscreen Top")
		(7 "B.SilkS" user "Ref Des/Silkscreen Bottom")
		(1 "F.Mask" user "Board Geometry/Soldermask Top")
		(3 "B.Mask" user "Board Geometry/Soldermask Bottom")
		(17 "Dwgs.User" user "User.Drawings")
		(19 "Cmts.User" user "User.Comments")
		(21 "Eco1.User" user "User.Eco1")
		(23 "Eco2.User" user "User.Eco2")
		(25 "Edge.Cuts" user "Board Geometry/Outline")
		(27 "Margin" user)
		(31 "F.CrtYd" user "Package Geometry/Place Bound Top")
		(29 "B.CrtYd" user "Package Geometry/Place Bound Bottom")
		(35 "F.Fab" user "Ref Des/Assembly Top")
		(33 "B.Fab" user "Ref Des/Assembly Bottom")
	)
	(footprint ""
		(layer "F.Cu")
		(at 167.899842 -160.50006)
		(property "Reference" "H86"
			(at -5.718302 -4.55549 0)
			(unlocked yes)
			(layer "F.SilkS")
			(effects
				(font
					(size 0.7874 0.5842)
					(thickness 0.1524)
				)
				(justify left)
			)
		)
		(property "Value" ""
			(at 0 0 0)
			(layer "F.Fab")
			(effects
				(font
					(size 1.27 1.27)
				)
			)
		)
		(duplicate_pad_numbers_are_jumpers no)
		(pad "1" thru_hole circle
			(at 0 0)
			(size 10.0076 10.0076)
			(drill 5.6134)
			(layers "*.Cu" "*.Mask")
			(remove_unused_layers no)
			(net "GND")
			(clearance -1.9431)
		)
	)
	(footprint ""
		(layer "F.Cu")
		(at 199.4916 -93.98 -90)
		(property "Reference" "U337"
			(at -2.159 0.701548 90)
			(unlocked yes)
			(layer "F.SilkS")
			(effects
				(font
					(size 0.7874 0.5842)
					(thickness 0.1524)
				)
				(justify left)
			)
		)
		(property "Value" ""
			(at 0 0 270)
			(layer "F.Fab")
			(effects
				(font
					(size 1.27 1.27)
				)
			)
		)
		(duplicate_pad_numbers_are_jumpers no)
		(fp_line
			(start -1.868424 1.519936)
			(end 1.868424 1.519936)
			(stroke
				(width 0.1524)
				(type default)
			)
			(layer "F.SilkS")
		)
		(fp_line
			(start 1.868424 1.519936)
			(end 1.868424 -1.519936)
			(stroke
				(width 0.1524)
				(type default)
			)
			(layer "F.SilkS")
		)
		(fp_line
			(start -1.868424 -1.519936)
			(end -1.868424 1.519936)
			(stroke
				(width 0.1524)
				(type default)
			)
			(layer "F.SilkS")
		)
		(fp_line
			(start 1.868424 -1.519936)
			(end -1.868424 -1.519936)
			(stroke
				(width 0.1524)
				(type default)
			)
			(layer "F.SilkS")
		)
		(fp_line
			(start -0.700024 1.519936)
			(end 0.700024 1.519936)
			(stroke
				(width 0.1)
				(type default)
			)
			(layer "F.Fab")
		)
		(fp_line
			(start 0.700024 1.519936)
			(end 0.700024 -1.519936)
			(stroke
				(width 0.1)
				(type default)
			)
			(layer "F.Fab")
		)
		(fp_line
			(start -0.700024 -1.519936)
			(end -0.700024 1.519936)
			(stroke
				(width 0.1)
				(type default)
			)
			(layer "F.Fab")
		)
		(fp_line
			(start 0.700024 -1.519936)
			(end -0.700024 -1.519936)
			(stroke
				(width 0.1)
				(type default)
			)
			(layer "F.Fab")
		)
		(pad "1" smd rect
			(at -1.18491 -0.94996 180)
			(size 0.6096 1.0668)
			(layers "F.Cu" "F.Mask" "F.Paste")
			(net "UV_ADR_P2V5_COMP")
		)
		(pad "2" smd rect
			(at -1.18491 0.94996 180)
			(size 0.6096 1.0668)
			(layers "F.Cu" "F.Mask" "F.Paste")
			(net "GND")
		)
		(pad "3" smd rect
			(at 1.18491 0 180)
			(size 0.6096 1.0668)
			(layers "F.Cu" "F.Mask" "F.Paste")
			(net "Net_8628")
		)
	)
	(footprint ""
		(layer "F.Cu")
		(at 27.598878 -16.099536 90)
		(property "Reference" "C814"
			(at 0 0 90)
			(layer "F.SilkS")
			(hide yes)
			(effects
				(font
					(size 1.27 1.27)
				)
			)
		)
		(property "Value" ""
			(at 0 0 90)
			(layer "F.Fab")
			(effects
				(font
					(size 1.27 1.27)
				)
			)
		)
		(duplicate_pad_numbers_are_jumpers no)
		(fp_line
			(start 0.299974 -0.150114)
			(end 0.299974 0.150114)
			(stroke
				(width 0.1)
				(type default)
			)
			(layer "F.Fab")
		)
		(fp_line
			(start -0.299974 -0.150114)
			(end 0.299974 -0.150114)
			(stroke
				(width 0.1)
				(type default)
			)
			(layer "F.Fab")
		)
		(fp_line
			(start 0.299974 0.150114)
			(end -0.299974 0.150114)
			(stroke
				(width 0.1)
				(type default)
			)
			(layer "F.Fab")
		)
		(fp_line
			(start -0.299974 0.150114)
			(end -0.299974 -0.150114)
			(stroke
				(width 0.1)
				(type default)
			)
			(layer "F.Fab")
		)
		(pad "1" smd rect
			(at -0.2667 0 90)
			(size 0.3048 0.381)
			(layers "F.Cu" "F.Mask" "F.Paste")
			(net "P5E_CPU1_PE1_TX_C_DN<11>")
		)
		(pad "2" smd rect
			(at 0.2667 0 90)
			(size 0.3048 0.381)
			(layers "F.Cu" "F.Mask" "F.Paste")
			(net "P5E_CPU1_PE1_TX_DN<11>")
		)
	)
	(footprint ""
		(layer "F.Cu")
		(at 315.405008 -408.517344 -90)
		(property "Reference" "C909"
			(at 0 0 270)
			(layer "F.SilkS")
			(hide yes)
			(effects
				(font
					(size 1.27 1.27)
				)
			)
		)
		(property "Value" ""
			(at 0 0 270)
			(layer "F.Fab")
			(effects
				(font
					(size 1.27 1.27)
				)
			)
		)
		(duplicate_pad_numbers_are_jumpers no)
		(fp_line
			(start -0.299974 0.150114)
			(end -0.299974 -0.150114)
			(stroke
				(width 0.1)
				(type default)
			)
			(layer "F.Fab")
		)
		(fp_line
			(start 0.299974 0.150114)
			(end -0.299974 0.150114)
			(stroke
				(width 0.1)
				(type default)
			)
			(layer "F.Fab")
		)
		(fp_line
			(start -0.299974 -0.150114)
			(end 0.299974 -0.150114)
			(stroke
				(width 0.1)
				(type default)
			)
			(layer "F.Fab")
		)
		(fp_line
			(start 0.299974 -0.150114)
			(end 0.299974 0.150114)
			(stroke
				(width 0.1)
				(type default)
			)
			(layer "F.Fab")
		)
		(pad "1" smd rect
			(at -0.2667 0 270)
			(size 0.3048 0.381)
			(layers "F.Cu" "F.Mask" "F.Paste")
			(net "P5E_CPU0_PE0_TX_C_DP<12>")
		)
		(pad "2" smd rect
			(at 0.2667 0 270)
			(size 0.3048 0.381)
			(layers "F.Cu" "F.Mask" "F.Paste")
			(net "P5E_CPU0_PE0_TX_DP<12>")
		)
	)
)
